FILE_TYPE = CONNECTIVITY;
{Allegro Design Entry HDL 16.6-p007 (v16-6-112F) 10/10/2012}
"PAGE_NUMBER" = 112;
0"NC";
1"PVCCIO_CPU0\g";
2"PVCCIO_CPU0\g";
3"P1V05_PCH_STBY\g";
4"GND\g";
5"PVCCIO_CPU0\g";
6"PVCCIO_CPU1\g";
7"GND\g";
8"GND\g";
9"P3V3_STBY\g";
10"P3V3_STBY\g";
11"PVCCIO_CPU0\g";
12"P3V3_STBY\g";
13"P3V3_STBY\g";
14"GND\g";
15"GND\g";
16"PVCCIO_CPU0\g";
17"GND\g";
18"GND\g";
19"XDP_PREQ_N";
20"XDP_PRDY_N";
21"XDP_OBSFN_B0_MBP6_N";
22"XDP_OBSFN_B1_MBP7_N";
23"PWRGD_PVCCIN_CPU0";
24"XDP_TDI";
25"XDP_TDO";
26"XDP_TMS";
27"XDP_TRST_N";
28"XDP_PCH_TCK1";
29"XDP_TRST_N";
30"XDP_CPU_OBSFN_B1_MBP7_N";
31"XDP_CPU_PREQ_N";
32"XDP_CPU_PRDY_N";
33"XDP_CPU_OBSFN_B0_MBP6_N";
34"XDP_CPU_TDI";
35"XDP_CPU_TDO";
36"XDP_CPU_TMS";
37"XDP_CPU_TRST_N";
38"XDP_PCH_CPU_TCK0";
39"XDP_PRDY_N";
40"XDP_PREQ_N";
41"XDP_TMS";
42"XDP_TDI";
43"XDP_TDO";
44"XDP_CPU_TRST_N";
45"XDP_CPU_TCK0";
46"XDP_CPU_PRDY_N";
47"XDP_CPU_PREQ_N";
48"XDP_CPU_TMS";
49"XDP_CPU1_TDI";
50"XDP_CPU_TDI";
51"XDP_CPU0_TDO";
52"XDP_CPU_MBP0_N";
53"XDP_CPU1_TDO";
54"XDP_CPU_MBP1_N";
55"XDP_CPU_OBSFN_B1_MBP7_N";
56"XDP_CPU_MBP0_N";
57"XDP_CPU_MBP1_N";
58"XDP_CPU_OBSFN_B0_MBP6_N";
59"XDP_CPU0_TDO";
60"FM_CPU1_SKTOCC_LVT3_N";
61"XDP_CPU1_TDI";
62"XDP_CPU_TDO";
63"XDP_CPU1_TDO";
64"XDP_CPU0_TDO";
65"FM_CPU1_SKTOCC_LVT3_N";
%"TTL3126"
"3","(-2200,2425)","0","mstr_ttl","I108";
;
ROOM"DEBUG"
CDS_LOCATION"U1L1"
CDS_LIB"mstr_ttl"
HAS_FIXED_SIZE"4B"
PACK_TYPE"QFNLF"
MATERIAL"IC"
VALUE"74CBTLV3126"
PART_NUMBER"D18317-001"
LOCATION"U1L1"
POWER_GROUP"VCC=P3V3_STBY;GND=GND";
"OE <3>"
$SEC"1"
CDS_SEC"1"
$PN"1"23;
"OE <2>"
$SEC"2"
CDS_SEC"2"
$PN"4"23;
"OE <1>"
$SEC"3"
CDS_SEC"3"
$PN"10"23;
"OE <0>"
$SEC"4"
CDS_SEC"4"
$PN"13"23;
"A <3>"
$SEC"1"
CDS_SEC"1"
$PN"2"27;
"A <2>"
$SEC"2"
CDS_SEC"2"
$PN"5"26;
"A <0>"
$SEC"4"
CDS_SEC"4"
$PN"12"24;
"A <1>"
$SEC"3"
CDS_SEC"3"
$PN"9"25;
"B <3>"
$SEC"1"
CDS_SEC"1"
$PN"3"37;
"B <2>"
$SEC"2"
CDS_SEC"2"
$PN"6"36;
"B <1>"
$SEC"3"
CDS_SEC"3"
$PN"8"35;
"B <0>"
$SEC"4"
CDS_SEC"4"
$PN"11"34;
%"TTL3126"
"3","(-2200,1200)","0","mstr_ttl","I109";
;
ROOM"DEBUG"
CDS_LOCATION"U1L5"
HAS_FIXED_SIZE"4B"
CDS_LIB"mstr_ttl"
PACK_TYPE"QFNLF"
MATERIAL"IC"
VALUE"74CBTLV3126"
PART_NUMBER"D18317-001"
LOCATION"U1L5"
POWER_GROUP"VCC=P3V3_STBY;GND=GND";
"OE <3>"
$SEC"1"
CDS_SEC"1"
$PN"1"23;
"OE <2>"
$SEC"2"
CDS_SEC"2"
$PN"4"23;
"OE <1>"
$SEC"3"
CDS_SEC"3"
$PN"10"23;
"OE <0>"
$SEC"4"
CDS_SEC"4"
$PN"13"23;
"A <3>"
$SEC"1"
CDS_SEC"1"
$PN"2"22;
"A <2>"
$SEC"2"
CDS_SEC"2"
$PN"5"21;
"A <0>"
$SEC"4"
CDS_SEC"4"
$PN"12"19;
"A <1>"
$SEC"3"
CDS_SEC"3"
$PN"9"20;
"B <3>"
$SEC"1"
CDS_SEC"1"
$PN"3"30;
"B <2>"
$SEC"2"
CDS_SEC"2"
$PN"6"33;
"B <1>"
$SEC"3"
CDS_SEC"3"
$PN"8"32;
"B <0>"
$SEC"4"
CDS_SEC"4"
$PN"11"31;
%"RES"
"2","(3500,2400)","0","mstr_discrete","I120";
;
CDS_SEC"1"
ROOM"DEBUG"
CDS_LOCATION"R6T9"
SEC"1"
CDS_LIB"mstr_discrete"
SEC_TYPE"0402"
WATTAGE"1/16W"
MATERIAL"CHIP"
PACK_TYPE"0402"
TOLERANCE"1%"
VALUE"100.0"
PART_NUMBER"G21796-017"
LOCATION"R6T9";
"A"
$PN"1"1;
"B"
$PN"2"55;
%"RES"
"2","(3175,2400)","0","mstr_discrete","I121";
;
CDS_SEC"1"
ROOM"DEBUG"
CDS_LOCATION"R6T8"
SEC"1"
CDS_LIB"mstr_discrete"
SEC_TYPE"0402"
WATTAGE"1/16W"
MATERIAL"CHIP"
PACK_TYPE"0402"
TOLERANCE"1%"
VALUE"100.0"
PART_NUMBER"G21796-017"
LOCATION"R6T8";
"A"
$PN"1"1;
"B"
$PN"2"58;
%"PVCCIO_CPU0"
"1","(3500,2700)","0","mstr_symbols","I122";
;
HDL_POWER"PVCCIO_CPU0"
BODY_TYPE"PLUMBING"
CDS_LIB"mstr_symbols"
VOLTAGE"1.1V";
"G\NAC"1;
%"PVCCIO_CPU0"
"1","(1950,2725)","0","mstr_symbols","I123";
;
HDL_POWER"PVCCIO_CPU0"
BODY_TYPE"PLUMBING"
CDS_LIB"mstr_symbols"
VOLTAGE"1.1V";
"G\NAC"2;
%"P1V05_PCH_STBY"
"1","(-1200,4750)","0","mstr_symbols","I126";
;
HDL_POWER"P1V05_PCH_STBY"
BODY_TYPE"PLUMBING"
CDS_LIB"mstr_symbols"
VOLTAGE"1.05V";
"G\NAC"3;
%"74CBTLV1G125"
"1","(3075,3425)","0","mstr_ttl","I127";
;
CDS_SEC"1"
CDS_LOCATION"U1M4"
ROOM"DEBUG"
SEC"1"
BOM_COST"DEBUG"
CDS_LIB"mstr_ttl"
SEC_TYPE"SMLF"
MATERIAL"IC"
PACK_TYPE"SMLF"
PART_NUMBER"C88177-001"
LOCATION"U1M4"
POWER_GROUP"VCC=P3V3_STBY;GND=GND;";
"OE_N \B"
$PN"1"60;
"B"
$PN"4"61;
"A"
$PN"2"59;
%"CAP_A"
"1","(3550,3725)","2","dev_discrete","I131";
;
CDS_LOCATION"C1M30"
ROOM"DEBUG"
SEC"1"
SEC_TYPE"0402V"
CDS_SEC"1"
CDS_LIB"dev_discrete"
BOM_COST"DEBUG"
MATERIAL"X7R"
VOLTAGE"25V"
PACK_TYPE"0402V"
TOLERANCE"10%"
VALUE"0.01UF"
PART_NUMBER"A36096-045"
LOCATION"C1M30";
"B"
$PN"2"4;
"A"
$PN"1"9;
%"GND"
"1","(3550,3525)","0","mstr_symbols","I133";
;
HDL_POWER"GND"
ROOM"CPU_JTAG_DEBUG"
BODY_TYPE"PLUMBING"
CDS_LIB"mstr_symbols"
BOM_COST"DEBUG"
SIZE"1B"
VOLTAGE"0.0V";
"A\NAC"4;
%"PVCCIO_CPU0"
"1","(500,2675)","0","mstr_symbols","I134";
;
HDL_POWER"PVCCIO_CPU0"
BODY_TYPE"PLUMBING"
CDS_LIB"mstr_symbols"
VOLTAGE"1.1V";
"G\NAC"5;
%"PVCCIO_CPU1"
"1","(1225,2675)","0","mstr_symbols","I135";
;
HDL_POWER"PVCCIO_CPU1"
BODY_TYPE"PLUMBING"
CDS_LIB"mstr_symbols"
VOLTAGE"1.1V";
"G\NAC"6;
%"CAP"
"1","(-1125,1850)","0","mstr_discrete","I136";
;
CDS_SEC"1"
ROOM"DEBUG"
CDS_LOCATION"C1L1"
SEC"1"
SEC_TYPE"0402"
CDS_LIB"mstr_discrete"
MATERIAL"X6S"
VOLTAGE"16V"
PACK_TYPE"0402"
TOLERANCE"10%"
VALUE"1.0UF"
PART_NUMBER"D97712-011"
LOCATION"C1L1";
"A"
$PN"1"12;
"B"
$PN"2"7;
%"GND"
"1","(-1125,1675)","0","mstr_symbols","I138";
;
HDL_POWER"GND"
BODY_TYPE"PLUMBING"
SIZE"1B"
CDS_LIB"mstr_symbols"
VOLTAGE"0.0V";
"A\NAC"7;
%"CAP"
"1","(-1350,625)","0","mstr_discrete","I140";
;
CDS_SEC"1"
ROOM"DEBUG"
CDS_LOCATION"C1L19"
SEC"1"
SEC_TYPE"0402"
CDS_LIB"mstr_discrete"
MATERIAL"X6S"
VOLTAGE"16V"
PACK_TYPE"0402"
TOLERANCE"10%"
VALUE"1.0UF"
PART_NUMBER"D97712-011"
LOCATION"C1L19";
"A"
$PN"1"13;
"B"
$PN"2"8;
%"GND"
"1","(-1350,450)","0","mstr_symbols","I141";
;
HDL_POWER"GND"
BODY_TYPE"PLUMBING"
CDS_LIB"mstr_symbols"
SIZE"1B"
VOLTAGE"0.0V";
"A\NAC"8;
%"P3V3_STBY"
"1","(3550,3925)","0","mstr_symbols","I143";
;
HDL_POWER"P3V3_STBY"
BODY_TYPE"PLUMBING"
SIZE"1B"
CDS_LIB"mstr_symbols"
VOLTAGE"+3.3V";
"G\NAC"9;
%"P3V3_STBY"
"1","(2700,4300)","0","mstr_symbols","I144";
;
HDL_POWER"P3V3_STBY"
BODY_TYPE"PLUMBING"
CDS_LIB"mstr_symbols"
SIZE"1B"
VOLTAGE"+3.3V";
"G\NAC"10;
%"PVCCIO_CPU0"
"1","(2675,2700)","0","mstr_symbols","I147";
;
HDL_POWER"PVCCIO_CPU0"
BODY_TYPE"PLUMBING"
CDS_LIB"mstr_symbols"
VOLTAGE"1.1V";
"G\NAC"11;
%"P3V3_STBY"
"1","(-1125,2050)","0","mstr_symbols","I148";
;
HDL_POWER"P3V3_STBY"
BODY_TYPE"PLUMBING"
SIZE"1B"
CDS_LIB"mstr_symbols"
VOLTAGE"+3.3V";
"G\NAC"12;
%"P3V3_STBY"
"1","(-1350,800)","0","mstr_symbols","I149";
;
HDL_POWER"P3V3_STBY"
BODY_TYPE"PLUMBING"
CDS_LIB"mstr_symbols"
SIZE"1B"
VOLTAGE"+3.3V";
"G\NAC"13;
%"GND"
"1","(2175,4450)","0","mstr_symbols","I39";
;
HDL_POWER"GND"
ROOM"CPU_JTAG_DEBUG"
BODY_TYPE"PLUMBING"
SIZE"1B"
CDS_LIB"mstr_symbols"
BOM_COST"DEBUG"
VOLTAGE"0.0V";
"A\NAC"14;
%"NC7SB3157"
"1","(2600,4675)","2","mstr_analog","I40";
;
CDS_LOCATION"U1M7"
ROOM"DEBUG"
$SEC"1"
CDS_SEC"1"
CDS_LIB"mstr_analog"
BOM_COST"DEBUG"
MATERIAL"IC"
PACK_TYPE"SMLF"
PART_NUMBER"C99406-001"
LOCATION"U1M7";
"GND"
$PN"2"14;
"A"
$PN"4"62;
"VCC"
$PN"5"10;
"B1"
$PN"1"64;
"B0"
$PN"3"63;
"S"
$PN"6"65;
%"CAP_A"
"1","(3100,4025)","2","dev_discrete","I42";
;
CDS_LOCATION"C1M36"
ROOM"DEBUG"
SEC"1"
SEC_TYPE"0402V"
CDS_SEC"1"
CDS_LIB"dev_discrete"
BOM_COST"DEBUG"
MATERIAL"X7R"
VOLTAGE"25V"
PACK_TYPE"0402V"
TOLERANCE"10%"
VALUE"0.01UF"
PART_NUMBER"A36096-045"
LOCATION"C1M36";
"B"
$PN"2"15;
"A"
$PN"1"10;
%"CAP_A"
"1","(2700,4025)","2","dev_discrete","I47";
;
CDS_LOCATION"C1M37"
ROOM"DEBUG"
$SEC"1"
CDS_SEC"1"
CDS_LIB"dev_discrete"
BOM_COST"DEBUG"
MATERIAL"X6S"
VOLTAGE"6.3V"
PACK_TYPE"0402V"
TOLERANCE"10%"
VALUE"1.0UF"
PART_NUMBER"D97712-004"
LOCATION"C1M37";
"B"
$PN"2"15;
"A"
$PN"1"10;
%"GND"
"1","(2700,3675)","0","mstr_symbols","I48";
;
HDL_POWER"GND"
ROOM"CPU_JTAG_DEBUG"
BODY_TYPE"PLUMBING"
SIZE"1B"
CDS_LIB"mstr_symbols"
BOM_COST"DEBUG"
VOLTAGE"0.0V";
"A\NAC"15;
%"RES"
"2","(2675,2400)","0","mstr_discrete","I49";
;
CDS_SEC"1"
ROOM"DEBUG"
CDS_LOCATION"R6P46"
SEC"1"
SEC_TYPE"0402"
CDS_LIB"mstr_discrete"
WATTAGE"1/16W"
MATERIAL"CHIP"
PACK_TYPE"0402"
TOLERANCE"1%"
VALUE"100.0"
PART_NUMBER"G21796-017"
LOCATION"R6P46";
"A"
$PN"1"11;
"B"
$PN"2"57;
%"RES"
"2","(2325,2400)","0","mstr_discrete","I50";
;
CDS_SEC"1"
ROOM"DEBUG"
CDS_LOCATION"R7P30"
SEC"1"
SEC_TYPE"0402"
CDS_LIB"mstr_discrete"
WATTAGE"1/16W"
MATERIAL"CHIP"
PACK_TYPE"0402"
TOLERANCE"1%"
VALUE"100.0"
PART_NUMBER"G21796-017"
LOCATION"R7P30";
"A"
$PN"1"11;
"B"
$PN"2"56;
%"RES"
"2","(1950,2400)","0","mstr_discrete","I51";
;
CDS_SEC"1"
ROOM"DEBUG"
CDS_LOCATION"R1M3"
SEC"1"
SEC_TYPE"0402"
CDS_LIB"mstr_discrete"
WATTAGE"1/16W"
MATERIAL"CHIP"
PACK_TYPE"0402"
TOLERANCE"1%"
VALUE"100.0"
PART_NUMBER"G21796-017"
LOCATION"R1M3";
"A"
$PN"1"2;
"B"
$PN"2"46;
%"PVCCIO_CPU0"
"1","(1175,4150)","0","mstr_symbols","I52";
;
HDL_POWER"PVCCIO_CPU0"
BODY_TYPE"PLUMBING"
CDS_LIB"mstr_symbols"
VOLTAGE"1.1V";
"G\NAC"16;
%"RES"
"2","(1175,3800)","0","mstr_discrete","I53";
;
CDS_SEC"1"
ROOM"DEBUG"
CDS_LOCATION"R4P15"
SEC"1"
SEC_TYPE"0402"
CDS_LIB"mstr_discrete"
WATTAGE"1/16W"
MATERIAL"CHIP"
PACK_TYPE"0402"
TOLERANCE"1%"
VALUE"100.0"
PART_NUMBER"G21796-017"
LOCATION"R4P15";
"A"
$PN"1"16;
"B"
$PN"2"54;
%"RES"
"2","(1600,2400)","0","mstr_discrete","I54";
;
CDS_SEC"1"
ROOM"DEBUG"
CDS_LOCATION"R1M4"
SEC"1"
SEC_TYPE"0402"
CDS_LIB"mstr_discrete"
WATTAGE"1/16W"
MATERIAL"CHIP"
PACK_TYPE"0402"
TOLERANCE"1%"
VALUE"100.0"
PART_NUMBER"G21796-017"
LOCATION"R1M4";
"A"
$PN"1"2;
"B"
$PN"2"47;
%"RES"
"2","(1225,2400)","0","mstr_discrete","I55";
;
CDS_SEC"1"
ROOM"DEBUG"
CDS_LOCATION"R6T7"
SEC"1"
CDS_LIB"mstr_discrete"
SEC_TYPE"0402"
WATTAGE"1/16W"
MATERIAL"CHIP"
PACK_TYPE"0402"
TOLERANCE"1%"
VALUE"150.0"
PART_NUMBER"G21796-009"
LOCATION"R6T7";
"A"
$PN"1"6;
"B"
$PN"2"53;
%"RES"
"2","(875,2400)","0","mstr_discrete","I56";
;
CDS_SEC"1"
ROOM"DEBUG"
CDS_LOCATION"R6T6"
SEC"1"
CDS_LIB"mstr_discrete"
SEC_TYPE"0402"
WATTAGE"1/16W"
MATERIAL"CHIP"
PACK_TYPE"0402"
TOLERANCE"1%"
VALUE"150.0"
PART_NUMBER"G21796-009"
LOCATION"R6T6";
"A"
$PN"1"6;
"B"
$PN"2"49;
%"RES"
"2","(875,3825)","0","mstr_discrete","I57";
;
CDS_SEC"1"
ROOM"DEBUG"
CDS_LOCATION"R4P12"
SEC"1"
SEC_TYPE"0402"
CDS_LIB"mstr_discrete"
WATTAGE"1/16W"
MATERIAL"CHIP"
PACK_TYPE"0402"
TOLERANCE"1%"
VALUE"100.0"
PART_NUMBER"G21796-017"
LOCATION"R4P12";
"A"
$PN"1"16;
"B"
$PN"2"52;
%"RES"
"2","(575,3800)","0","mstr_discrete","I58";
;
CDS_SEC"1"
ROOM"DEBUG"
CDS_LOCATION"R4P23"
SEC"1"
CDS_LIB"mstr_discrete"
SEC_TYPE"0402"
WATTAGE"1/16W"
MATERIAL"CHIP"
PACK_TYPE"0402"
TOLERANCE"1%"
VALUE"150.0"
PART_NUMBER"G21796-009"
LOCATION"R4P23";
"A"
$PN"1"16;
"B"
$PN"2"51;
%"RES"
"2","(275,3800)","0","mstr_discrete","I59";
;
CDS_SEC"1"
ROOM"DEBUG"
CDS_LOCATION"R4P24"
SEC"1"
SEC_TYPE"0402"
CDS_LIB"mstr_discrete"
WATTAGE"1/16W"
MATERIAL"CHIP"
PACK_TYPE"0402"
TOLERANCE"1%"
VALUE"150.0"
PART_NUMBER"G21796-009"
LOCATION"R4P24";
"A"
$PN"1"16;
"B"
$PN"2"50;
%"RES"
"2","(500,2400)","0","mstr_discrete","I60";
;
CDS_SEC"1"
ROOM"DEBUG"
CDS_LOCATION"R1L15"
SEC"1"
CDS_LIB"mstr_discrete"
SEC_TYPE"0402"
WATTAGE"1/16W"
MATERIAL"CHIP"
PACK_TYPE"0402"
TOLERANCE"1%"
VALUE"150.0"
PART_NUMBER"G21796-009"
LOCATION"R1L15";
"A"
$PN"1"5;
"B"
$PN"2"48;
%"RES"
"2","(875,1100)","0","mstr_discrete","I61";
;
ROOM"DEBUG"
CDS_LOCATION"R7P29"
$SEC"1"
CDS_SEC"1"
BOM_COST"DEBUG"
CDS_LIB"mstr_discrete"
WATTAGE"1/16W"
MATERIAL"CHIP"
PACK_TYPE"0402"
TOLERANCE"1.0%"
VALUE"51.1"
PART_NUMBER"G21796-208"
LOCATION"R7P29";
"A"
$PN"1"45;
"B"
$PN"2"17;
%"RES"
"2","(500,1100)","0","mstr_discrete","I62";
;
CDS_SEC"1"
ROOM"DEBUG"
CDS_LOCATION"R6T5"
SEC"1"
SEC_TYPE"0402"
CDS_LIB"mstr_discrete"
BOM_COST"DEBUG"
WATTAGE"1/16W"
MATERIAL"CHIP"
PACK_TYPE"0402"
TOLERANCE"1%"
VALUE"1.00K"
PART_NUMBER"G21796-026"
LOCATION"R6T5";
"A"
$PN"1"44;
"B"
$PN"2"17;
%"GND"
"1","(500,725)","0","mstr_symbols","I74";
;
HDL_POWER"GND"
BODY_TYPE"PLUMBING"
CDS_LIB"mstr_symbols"
SIZE"1B"
VOLTAGE"0.0V";
"A\NAC"17;
%"RES"
"2","(-1200,4425)","0","mstr_discrete","I76";
;
CDS_SEC"1"
ROOM"DEBUG"
CDS_LOCATION"R1L39"
SEC"1"
SEC_TYPE"0402"
CDS_LIB"mstr_discrete"
WATTAGE"1/16W"
MATERIAL"CHIP"
PACK_TYPE"0402"
TOLERANCE"1%"
VALUE"100.0"
PART_NUMBER"G21796-017"
LOCATION"R1L39";
"A"
$PN"1"3;
"B"
$PN"2"39;
%"RES"
"2","(-1575,4425)","0","mstr_discrete","I77";
;
CDS_SEC"1"
ROOM"DEBUG"
CDS_LOCATION"R1L41"
SEC"1"
CDS_LIB"mstr_discrete"
SEC_TYPE"0402"
WATTAGE"1/16W"
MATERIAL"CHIP"
PACK_TYPE"0402"
TOLERANCE"1%"
VALUE"100.0"
PART_NUMBER"G21796-017"
LOCATION"R1L41";
"A"
$PN"1"3;
"B"
$PN"2"40;
%"RES"
"2","(-1950,4425)","0","mstr_discrete","I78";
;
CDS_SEC"1"
ROOM"DEBUG"
CDS_LOCATION"R9A11"
SEC"1"
SEC_TYPE"0402"
CDS_LIB"mstr_discrete"
WATTAGE"1/16W"
MATERIAL"CHIP"
PACK_TYPE"0402"
TOLERANCE"1%"
VALUE"150.0"
PART_NUMBER"G21796-009"
LOCATION"R9A11";
"A"
$PN"1"3;
"B"
$PN"2"43;
%"RES"
"2","(-2325,4425)","0","mstr_discrete","I79";
;
CDS_SEC"1"
ROOM"DEBUG"
CDS_LOCATION"R8A13"
SEC"1"
SEC_TYPE"0402"
CDS_LIB"mstr_discrete"
WATTAGE"1/16W"
MATERIAL"CHIP"
PACK_TYPE"0402"
TOLERANCE"1%"
VALUE"150.0"
PART_NUMBER"G21796-009"
LOCATION"R8A13";
"A"
$PN"1"3;
"B"
$PN"2"42;
%"RES"
"2","(-2700,4425)","0","mstr_discrete","I80";
;
CDS_SEC"1"
ROOM"DEBUG"
CDS_LOCATION"R8A14"
SEC"1"
SEC_TYPE"0402"
CDS_LIB"mstr_discrete"
WATTAGE"1/16W"
MATERIAL"CHIP"
PACK_TYPE"0402"
TOLERANCE"1%"
VALUE"150.0"
PART_NUMBER"G21796-009"
LOCATION"R8A14";
"A"
$PN"1"3;
"B"
$PN"2"41;
%"RES"
"2","(-1950,3600)","0","mstr_discrete","I85";
;
CDS_SEC"1"
ROOM"DEBUG"
CDS_LOCATION"R3M10"
SEC"1"
BOM_COST"DEBUG"
CDS_LIB"mstr_discrete"
SEC_TYPE"0402"
WATTAGE"1/16W"
MATERIAL"CHIP"
PACK_TYPE"0402"
TOLERANCE"1%"
VALUE"1.00K"
PART_NUMBER"G21796-026"
LOCATION"R3M10";
"A"
$PN"1"38;
"B"
$PN"2"18;
%"RES"
"2","(-2325,3600)","0","mstr_discrete","I94";
;
CDS_SEC"1"
ROOM"DEBUG"
CDS_LOCATION"R8B2"
SEC"1"
BOM_COST"DEBUG"
CDS_LIB"mstr_discrete"
SEC_TYPE"0402"
WATTAGE"1/16W"
MATERIAL"CHIP"
PACK_TYPE"0402"
TOLERANCE"1%"
VALUE"1.00K"
PART_NUMBER"G21796-026"
LOCATION"R8B2";
"A"
$PN"1"29;
"B"
$PN"2"18;
%"RES"
"2","(-2700,3600)","0","mstr_discrete","I95";
;
ROOM"DEBUG"
CDS_LOCATION"R8B1"
$SEC"1"
CDS_SEC"1"
CDS_LIB"mstr_discrete"
BOM_COST"DEBUG"
WATTAGE"1/16W"
MATERIAL"CHIP"
PACK_TYPE"0402"
TOLERANCE"1.0%"
VALUE"51.1"
PART_NUMBER"G21796-208"
LOCATION"R8B1";
"A"
$PN"1"28;
"B"
$PN"2"18;
%"GND"
"1","(-2700,3300)","0","mstr_symbols","I96";
;
HDL_POWER"GND"
BODY_TYPE"PLUMBING"
CDS_LIB"mstr_symbols"
SIZE"1B"
VOLTAGE"0.0V";
"A\NAC"18;
END.
